FILE_TYPE = CONNECTIVITY;
{Allegro Design Entry HDL 17.2-2016 S081 (4005846) 1/11/2022}
"PAGE_NUMBER" = 140;
0"NC";
END.
